(kicad_pcb
	(version 20260206)
	(generator "pcbnew")
	(generator_version "10.0")
	(general
		(thickness 1.6)
		(legacy_teardrops no)
	)
	(paper "A4")
	(title_block
		(title "01162023_DA0F0TEBIF0_F0T_Expander_BD_F_brd_V02_OCP.brd")
		(comment 1 "Grand Teton / footprints 3062-3067 of 9728")
	)
	(layers
		(0 "F.Cu" signal "TOP")
		(4 "In1.Cu" signal "GND")
		(6 "In2.Cu" signal "VCC")
		(8 "In3.Cu" signal "VCC1")
		(10 "In4.Cu" signal "GND1")
		(12 "In5.Cu" signal "IN1")
		(14 "In6.Cu" signal "GND2")
		(16 "In7.Cu" signal "IN2")
		(18 "In8.Cu" signal "GND3")
		(20 "In9.Cu" signal "IN3")
		(22 "In10.Cu" signal "GND4")
		(24 "In11.Cu" signal "IN4")
		(26 "In12.Cu" signal "GND5")
		(28 "In13.Cu" signal "IN5")
		(30 "In14.Cu" signal "GND6")
		(32 "In15.Cu" signal "IN6")
		(34 "In16.Cu" signal "GND7")
		(2 "B.Cu" signal "BOTTOM")
		(9 "F.Adhes" user "F.Adhesive")
		(11 "B.Adhes" user "B.Adhesive")
		(13 "F.Paste" user "Package Geometry/Pastemask Top")
		(15 "B.Paste" user "Package Geometry/Pastemask Bottom")
		(5 "F.SilkS" user "Ref Des/Silkscreen Top")
		(7 "B.SilkS" user "Ref Des/Silkscreen Bottom")
		(1 "F.Mask" user "Board Geometry/Soldermask Top")
		(3 "B.Mask" user "Board Geometry/Soldermask Bottom")
		(17 "Dwgs.User" user "User.Drawings")
		(19 "Cmts.User" user "User.Comments")
		(21 "Eco1.User" user "User.Eco1")
		(23 "Eco2.User" user "User.Eco2")
		(25 "Edge.Cuts" user "Board Geometry/Outline")
		(27 "Margin" user)
		(31 "F.CrtYd" user "Package Geometry/Place Bound Top")
		(29 "B.CrtYd" user "Package Geometry/Place Bound Bottom")
		(35 "F.Fab" user "Ref Des/Assembly Top")
		(33 "B.Fab" user "Ref Des/Assembly Bottom")
	)
	(footprint ""
		(layer "F.Cu")
		(at 192.582038 -37.025072)
		(property "Reference" "R5673"
			(at 0 0 0)
			(layer "F.SilkS")
			(hide yes)
			(effects
				(font
					(size 1.27 1.27)
				)
			)
		)
		(property "Value" ""
			(at 0 0 0)
			(layer "F.Fab")
			(effects
				(font
					(size 1.27 1.27)
				)
			)
		)
		(duplicate_pad_numbers_are_jumpers no)
		(fp_line
			(start -0.7874 -0.4064)
			(end 0.7874 -0.4064)
			(stroke
				(width 0.1524)
				(type default)
			)
			(layer "F.SilkS")
		)
		(fp_line
			(start -0.7874 0.4064)
			(end -0.7874 -0.4064)
			(stroke
				(width 0.1524)
				(type default)
			)
			(layer "F.SilkS")
		)
		(fp_line
			(start 0.7874 -0.4064)
			(end 0.7874 0.4064)
			(stroke
				(width 0.1524)
				(type default)
			)
			(layer "F.SilkS")
		)
		(fp_line
			(start 0.7874 0.4064)
			(end -0.7874 0.4064)
			(stroke
				(width 0.1524)
				(type default)
			)
			(layer "F.SilkS")
		)
		(fp_line
			(start -0.67945 -0.305054)
			(end -0.12065 -0.305054)
			(stroke
				(width 0.1)
				(type default)
			)
			(layer "F.Fab")
		)
		(fp_line
			(start -0.67945 0.3048)
			(end -0.67945 -0.305054)
			(stroke
				(width 0.1)
				(type default)
			)
			(layer "F.Fab")
		)
		(fp_line
			(start -0.12065 -0.305054)
			(end -0.12065 -0.2794)
			(stroke
				(width 0.1)
				(type default)
			)
			(layer "F.Fab")
		)
		(fp_line
			(start -0.12065 -0.2794)
			(end 0.12065 -0.2794)
			(stroke
				(width 0.1)
				(type default)
			)
			(layer "F.Fab")
		)
		(fp_line
			(start -0.12065 0.2794)
			(end -0.12065 0.3048)
			(stroke
				(width 0.1)
				(type default)
			)
			(layer "F.Fab")
		)
		(fp_line
			(start -0.12065 0.3048)
			(end -0.67945 0.3048)
			(stroke
				(width 0.1)
				(type default)
			)
			(layer "F.Fab")
		)
		(fp_line
			(start 0.120396 0.2794)
			(end -0.12065 0.2794)
			(stroke
				(width 0.1)
				(type default)
			)
			(layer "F.Fab")
		)
		(fp_line
			(start 0.120396 0.3048)
			(end 0.120396 0.2794)
			(stroke
				(width 0.1)
				(type default)
			)
			(layer "F.Fab")
		)
		(fp_line
			(start 0.12065 -0.3048)
			(end 0.67945 -0.3048)
			(stroke
				(width 0.1)
				(type default)
			)
			(layer "F.Fab")
		)
		(fp_line
			(start 0.12065 -0.2794)
			(end 0.12065 -0.3048)
			(stroke
				(width 0.1)
				(type default)
			)
			(layer "F.Fab")
		)
		(fp_line
			(start 0.67945 -0.3048)
			(end 0.67945 0.3048)
			(stroke
				(width 0.1)
				(type default)
			)
			(layer "F.Fab")
		)
		(fp_line
			(start 0.67945 0.3048)
			(end 0.120396 0.3048)
			(stroke
				(width 0.1)
				(type default)
			)
			(layer "F.Fab")
		)
		(pad "1" smd circle
			(at -0.40005 0)
			(size 0 0)
			(layers "F.Cu" "F.Mask" "F.Paste")
			(net "RST_SMB_SSD_R_N")
		)
		(pad "2" smd circle
			(at 0.40005 0)
			(size 0 0)
			(layers "F.Cu" "F.Mask" "F.Paste")
			(net "RST_SMB_SSD7_N")
		)
	)
	(footprint ""
		(layer "F.Cu")
		(at 228.6508 -231.4194 -90)
		(property "Reference" "R4538"
			(at 0 0 270)
			(layer "F.SilkS")
			(hide yes)
			(effects
				(font
					(size 1.27 1.27)
				)
			)
		)
		(property "Value" ""
			(at 0 0 270)
			(layer "F.Fab")
			(effects
				(font
					(size 1.27 1.27)
				)
			)
		)
		(duplicate_pad_numbers_are_jumpers no)
		(fp_line
			(start -0.7874 0.4064)
			(end -0.7874 -0.4064)
			(stroke
				(width 0.1524)
				(type default)
			)
			(layer "F.SilkS")
		)
		(fp_line
			(start 0.7874 0.4064)
			(end -0.7874 0.4064)
			(stroke
				(width 0.1524)
				(type default)
			)
			(layer "F.SilkS")
		)
		(fp_line
			(start -0.7874 -0.4064)
			(end 0.7874 -0.4064)
			(stroke
				(width 0.1524)
				(type default)
			)
			(layer "F.SilkS")
		)
		(fp_line
			(start 0.7874 -0.4064)
			(end 0.7874 0.4064)
			(stroke
				(width 0.1524)
				(type default)
			)
			(layer "F.SilkS")
		)
		(fp_line
			(start -0.67945 0.3048)
			(end -0.67945 -0.305054)
			(stroke
				(width 0.1)
				(type default)
			)
			(layer "F.Fab")
		)
		(fp_line
			(start -0.12065 0.3048)
			(end -0.67945 0.3048)
			(stroke
				(width 0.1)
				(type default)
			)
			(layer "F.Fab")
		)
		(fp_line
			(start 0.120396 0.3048)
			(end 0.120396 0.2794)
			(stroke
				(width 0.1)
				(type default)
			)
			(layer "F.Fab")
		)
		(fp_line
			(start 0.67945 0.3048)
			(end 0.120396 0.3048)
			(stroke
				(width 0.1)
				(type default)
			)
			(layer "F.Fab")
		)
		(fp_line
			(start -0.12065 0.2794)
			(end -0.12065 0.3048)
			(stroke
				(width 0.1)
				(type default)
			)
			(layer "F.Fab")
		)
		(fp_line
			(start 0.120396 0.2794)
			(end -0.12065 0.2794)
			(stroke
				(width 0.1)
				(type default)
			)
			(layer "F.Fab")
		)
		(fp_line
			(start -0.12065 -0.2794)
			(end 0.12065 -0.2794)
			(stroke
				(width 0.1)
				(type default)
			)
			(layer "F.Fab")
		)
		(fp_line
			(start 0.12065 -0.2794)
			(end 0.12065 -0.3048)
			(stroke
				(width 0.1)
				(type default)
			)
			(layer "F.Fab")
		)
		(fp_line
			(start 0.12065 -0.3048)
			(end 0.67945 -0.3048)
			(stroke
				(width 0.1)
				(type default)
			)
			(layer "F.Fab")
		)
		(fp_line
			(start 0.67945 -0.3048)
			(end 0.67945 0.3048)
			(stroke
				(width 0.1)
				(type default)
			)
			(layer "F.Fab")
		)
		(fp_line
			(start -0.67945 -0.305054)
			(end -0.12065 -0.305054)
			(stroke
				(width 0.1)
				(type default)
			)
			(layer "F.Fab")
		)
		(fp_line
			(start -0.12065 -0.305054)
			(end -0.12065 -0.2794)
			(stroke
				(width 0.1)
				(type default)
			)
			(layer "F.Fab")
		)
		(pad "1" smd circle
			(at -0.40005 0 270)
			(size 0 0)
			(layers "F.Cu" "F.Mask" "F.Paste")
			(net "NIC2_MAIN_PWR_BIC_EN_R")
		)
		(pad "2" smd circle
			(at 0.40005 0 270)
			(size 0 0)
			(layers "F.Cu" "F.Mask" "F.Paste")
			(net "NIC2_MAIN_PWR_BIC_EN")
		)
	)
	(footprint ""
		(layer "F.Cu")
		(at 392.24712 -55.63489 90)
		(property "Reference" "PC419"
			(at 0 0 90)
			(layer "F.SilkS")
			(hide yes)
			(effects
				(font
					(size 1.27 1.27)
				)
			)
		)
		(property "Value" ""
			(at 0 0 90)
			(layer "F.Fab")
			(effects
				(font
					(size 1.27 1.27)
				)
			)
		)
		(duplicate_pad_numbers_are_jumpers no)
		(fp_line
			(start 1.524 -0.762)
			(end 1.524 0.762)
			(stroke
				(width 0.1524)
				(type default)
			)
			(layer "F.SilkS")
		)
		(fp_line
			(start -1.524 -0.762)
			(end 1.524 -0.762)
			(stroke
				(width 0.1524)
				(type default)
			)
			(layer "F.SilkS")
		)
		(fp_line
			(start 1.524 0.762)
			(end -1.524 0.762)
			(stroke
				(width 0.1524)
				(type default)
			)
			(layer "F.SilkS")
		)
		(fp_line
			(start -1.524 0.762)
			(end -1.524 -0.762)
			(stroke
				(width 0.1524)
				(type default)
			)
			(layer "F.SilkS")
		)
		(fp_line
			(start 1.1049 -0.724916)
			(end -1.1049 -0.724916)
			(stroke
				(width 0.1)
				(type default)
			)
			(layer "F.Fab")
		)
		(fp_line
			(start -1.1049 -0.724916)
			(end -1.1049 0.724916)
			(stroke
				(width 0.1)
				(type default)
			)
			(layer "F.Fab")
		)
		(fp_line
			(start 1.1049 0.724916)
			(end 1.1049 -0.724916)
			(stroke
				(width 0.1)
				(type default)
			)
			(layer "F.Fab")
		)
		(fp_line
			(start -1.1049 0.724916)
			(end 1.1049 0.724916)
			(stroke
				(width 0.1)
				(type default)
			)
			(layer "F.Fab")
		)
		(pad "1" smd rect
			(at -0.889 0 270)
			(size 1.016 1.27)
			(layers "F.Cu" "F.Mask" "F.Paste")
			(net "P12V_SSD13_R")
		)
		(pad "2" smd rect
			(at 0.889 0 270)
			(size 1.016 1.27)
			(layers "F.Cu" "F.Mask" "F.Paste")
			(net "GND")
		)
	)
	(footprint ""
		(layer "F.Cu")
		(at 161.83864 -44.341542 90)
		(property "Reference" "C314"
			(at 0 0 90)
			(layer "F.SilkS")
			(hide yes)
			(effects
				(font
					(size 1.27 1.27)
				)
			)
		)
		(property "Value" ""
			(at 0 0 90)
			(layer "F.Fab")
			(effects
				(font
					(size 1.27 1.27)
				)
			)
		)
		(duplicate_pad_numbers_are_jumpers no)
		(fp_line
			(start 0.7874 -0.4064)
			(end 0.7874 0.4064)
			(stroke
				(width 0.1524)
				(type default)
			)
			(layer "F.SilkS")
		)
		(fp_line
			(start -0.7874 -0.4064)
			(end 0.7874 -0.4064)
			(stroke
				(width 0.1524)
				(type default)
			)
			(layer "F.SilkS")
		)
		(fp_line
			(start 0.7874 0.4064)
			(end -0.7874 0.4064)
			(stroke
				(width 0.1524)
				(type default)
			)
			(layer "F.SilkS")
		)
		(fp_line
			(start -0.7874 0.4064)
			(end -0.7874 -0.4064)
			(stroke
				(width 0.1524)
				(type default)
			)
			(layer "F.SilkS")
		)
		(fp_line
			(start -0.12065 -0.305054)
			(end -0.12065 -0.2794)
			(stroke
				(width 0.1)
				(type default)
			)
			(layer "F.Fab")
		)
		(fp_line
			(start -0.67945 -0.305054)
			(end -0.12065 -0.305054)
			(stroke
				(width 0.1)
				(type default)
			)
			(layer "F.Fab")
		)
		(fp_line
			(start 0.67945 -0.3048)
			(end 0.67945 0.3048)
			(stroke
				(width 0.1)
				(type default)
			)
			(layer "F.Fab")
		)
		(fp_line
			(start 0.12065 -0.3048)
			(end 0.67945 -0.3048)
			(stroke
				(width 0.1)
				(type default)
			)
			(layer "F.Fab")
		)
		(fp_line
			(start 0.12065 -0.2794)
			(end 0.12065 -0.3048)
			(stroke
				(width 0.1)
				(type default)
			)
			(layer "F.Fab")
		)
		(fp_line
			(start -0.12065 -0.2794)
			(end 0.12065 -0.2794)
			(stroke
				(width 0.1)
				(type default)
			)
			(layer "F.Fab")
		)
		(fp_line
			(start 0.120396 0.2794)
			(end -0.12065 0.2794)
			(stroke
				(width 0.1)
				(type default)
			)
			(layer "F.Fab")
		)
		(fp_line
			(start -0.12065 0.2794)
			(end -0.12065 0.3048)
			(stroke
				(width 0.1)
				(type default)
			)
			(layer "F.Fab")
		)
		(fp_line
			(start 0.67945 0.3048)
			(end 0.120396 0.3048)
			(stroke
				(width 0.1)
				(type default)
			)
			(layer "F.Fab")
		)
		(fp_line
			(start 0.120396 0.3048)
			(end 0.120396 0.2794)
			(stroke
				(width 0.1)
				(type default)
			)
			(layer "F.Fab")
		)
		(fp_line
			(start -0.12065 0.3048)
			(end -0.67945 0.3048)
			(stroke
				(width 0.1)
				(type default)
			)
			(layer "F.Fab")
		)
		(fp_line
			(start -0.67945 0.3048)
			(end -0.67945 -0.305054)
			(stroke
				(width 0.1)
				(type default)
			)
			(layer "F.Fab")
		)
		(pad "1" smd circle
			(at -0.40005 0 90)
			(size 0 0)
			(layers "F.Cu" "F.Mask" "F.Paste")
			(net "P12V_SSD5_VIN_P")
		)
		(pad "2" smd circle
			(at 0.40005 0 90)
			(size 0 0)
			(layers "F.Cu" "F.Mask" "F.Paste")
			(net "P12V_SSD5_VIN_N")
		)
	)
	(footprint ""
		(layer "F.Cu")
		(at 351.17532 -64.102234 180)
		(property "Reference" "PR7091"
			(at 0 0 180)
			(layer "F.SilkS")
			(hide yes)
			(effects
				(font
					(size 1.27 1.27)
				)
			)
		)
		(property "Value" ""
			(at 0 0 180)
			(layer "F.Fab")
			(effects
				(font
					(size 1.27 1.27)
				)
			)
		)
		(duplicate_pad_numbers_are_jumpers no)
		(fp_line
			(start 0.7874 0.4064)
			(end -0.7874 0.4064)
			(stroke
				(width 0.1524)
				(type default)
			)
			(layer "F.SilkS")
		)
		(fp_line
			(start 0.7874 -0.4064)
			(end 0.7874 0.4064)
			(stroke
				(width 0.1524)
				(type default)
			)
			(layer "F.SilkS")
		)
		(fp_line
			(start -0.7874 0.4064)
			(end -0.7874 -0.4064)
			(stroke
				(width 0.1524)
				(type default)
			)
			(layer "F.SilkS")
		)
		(fp_line
			(start -0.7874 -0.4064)
			(end 0.7874 -0.4064)
			(stroke
				(width 0.1524)
				(type default)
			)
			(layer "F.SilkS")
		)
		(fp_line
			(start 0.67945 0.3048)
			(end 0.120396 0.3048)
			(stroke
				(width 0.1)
				(type default)
			)
			(layer "F.Fab")
		)
		(fp_line
			(start 0.67945 -0.3048)
			(end 0.67945 0.3048)
			(stroke
				(width 0.1)
				(type default)
			)
			(layer "F.Fab")
		)
		(fp_line
			(start 0.12065 -0.2794)
			(end 0.12065 -0.3048)
			(stroke
				(width 0.1)
				(type default)
			)
			(layer "F.Fab")
		)
		(fp_line
			(start 0.12065 -0.3048)
			(end 0.67945 -0.3048)
			(stroke
				(width 0.1)
				(type default)
			)
			(layer "F.Fab")
		)
		(fp_line
			(start 0.120396 0.3048)
			(end 0.120396 0.2794)
			(stroke
				(width 0.1)
				(type default)
			)
			(layer "F.Fab")
		)
		(fp_line
			(start 0.120396 0.2794)
			(end -0.12065 0.2794)
			(stroke
				(width 0.1)
				(type default)
			)
			(layer "F.Fab")
		)
		(fp_line
			(start -0.12065 0.3048)
			(end -0.67945 0.3048)
			(stroke
				(width 0.1)
				(type default)
			)
			(layer "F.Fab")
		)
		(fp_line
			(start -0.12065 0.2794)
			(end -0.12065 0.3048)
			(stroke
				(width 0.1)
				(type default)
			)
			(layer "F.Fab")
		)
		(fp_line
			(start -0.12065 -0.2794)
			(end 0.12065 -0.2794)
			(stroke
				(width 0.1)
				(type default)
			)
			(layer "F.Fab")
		)
		(fp_line
			(start -0.12065 -0.305054)
			(end -0.12065 -0.2794)
			(stroke
				(width 0.1)
				(type default)
			)
			(layer "F.Fab")
		)
		(fp_line
			(start -0.67945 0.3048)
			(end -0.67945 -0.305054)
			(stroke
				(width 0.1)
				(type default)
			)
			(layer "F.Fab")
		)
		(fp_line
			(start -0.67945 -0.305054)
			(end -0.12065 -0.305054)
			(stroke
				(width 0.1)
				(type default)
			)
			(layer "F.Fab")
		)
		(pad "1" smd circle
			(at -0.40005 0 180)
			(size 0 0)
			(layers "F.Cu" "F.Mask" "F.Paste")
			(net "P12V_SSD12_PG_G1")
		)
		(pad "2" smd circle
			(at 0.40005 0 180)
			(size 0 0)
			(layers "F.Cu" "F.Mask" "F.Paste")
			(net "GND")
		)
	)
	(footprint ""
		(layer "F.Cu")
		(at 258.574286 -252.356874 -90)
		(property "Reference" "R1358"
			(at 0 0 270)
			(layer "F.SilkS")
			(hide yes)
			(effects
				(font
					(size 1.27 1.27)
				)
			)
		)
		(property "Value" ""
			(at 0 0 270)
			(layer "F.Fab")
			(effects
				(font
					(size 1.27 1.27)
				)
			)
		)
		(duplicate_pad_numbers_are_jumpers no)
		(fp_line
			(start -0.7874 0.4064)
			(end -0.7874 -0.4064)
			(stroke
				(width 0.1524)
				(type default)
			)
			(layer "F.SilkS")
		)
		(fp_line
			(start 0.7874 0.4064)
			(end -0.7874 0.4064)
			(stroke
				(width 0.1524)
				(type default)
			)
			(layer "F.SilkS")
		)
		(fp_line
			(start -0.7874 -0.4064)
			(end 0.7874 -0.4064)
			(stroke
				(width 0.1524)
				(type default)
			)
			(layer "F.SilkS")
		)
		(fp_line
			(start 0.7874 -0.4064)
			(end 0.7874 0.4064)
			(stroke
				(width 0.1524)
				(type default)
			)
			(layer "F.SilkS")
		)
		(fp_line
			(start -0.67945 0.3048)
			(end -0.67945 -0.305054)
			(stroke
				(width 0.1)
				(type default)
			)
			(layer "F.Fab")
		)
		(fp_line
			(start -0.12065 0.3048)
			(end -0.67945 0.3048)
			(stroke
				(width 0.1)
				(type default)
			)
			(layer "F.Fab")
		)
		(fp_line
			(start 0.120396 0.3048)
			(end 0.120396 0.2794)
			(stroke
				(width 0.1)
				(type default)
			)
			(layer "F.Fab")
		)
		(fp_line
			(start 0.67945 0.3048)
			(end 0.120396 0.3048)
			(stroke
				(width 0.1)
				(type default)
			)
			(layer "F.Fab")
		)
		(fp_line
			(start -0.12065 0.2794)
			(end -0.12065 0.3048)
			(stroke
				(width 0.1)
				(type default)
			)
			(layer "F.Fab")
		)
		(fp_line
			(start 0.120396 0.2794)
			(end -0.12065 0.2794)
			(stroke
				(width 0.1)
				(type default)
			)
			(layer "F.Fab")
		)
		(fp_line
			(start -0.12065 -0.2794)
			(end 0.12065 -0.2794)
			(stroke
				(width 0.1)
				(type default)
			)
			(layer "F.Fab")
		)
		(fp_line
			(start 0.12065 -0.2794)
			(end 0.12065 -0.3048)
			(stroke
				(width 0.1)
				(type default)
			)
			(layer "F.Fab")
		)
		(fp_line
			(start 0.12065 -0.3048)
			(end 0.67945 -0.3048)
			(stroke
				(width 0.1)
				(type default)
			)
			(layer "F.Fab")
		)
		(fp_line
			(start 0.67945 -0.3048)
			(end 0.67945 0.3048)
			(stroke
				(width 0.1)
				(type default)
			)
			(layer "F.Fab")
		)
		(fp_line
			(start -0.67945 -0.305054)
			(end -0.12065 -0.305054)
			(stroke
				(width 0.1)
				(type default)
			)
			(layer "F.Fab")
		)
		(fp_line
			(start -0.12065 -0.305054)
			(end -0.12065 -0.2794)
			(stroke
				(width 0.1)
				(type default)
			)
			(layer "F.Fab")
		)
		(pad "1" smd circle
			(at -0.40005 0 270)
			(size 0 0)
			(layers "F.Cu" "F.Mask" "F.Paste")
			(net "GND")
		)
		(pad "2" smd circle
			(at 0.40005 0 270)
			(size 0 0)
			(layers "F.Cu" "F.Mask" "F.Paste")
			(net "PEX2_MODE_SEL2")
		)
	)
)
